# S9S_MB_2U (Grand Teton) — schematic netlist excerpt (pin names and nets, part order shuffled) for the footprints in the layout excerpt that follows; sources: Cadence DE-HDL packaged netlist, KiCad conversion of 03242023_DA0F0TMBIJ0_F0T_Motherboard_J_brd_V01_OCP.brd

R706  Q_RES  10K 1% EMPTY  pkg 0402LF  page 129 : A = RST_PLD_CPU0_DRAM_AB_N ; B = GND
R3892  Q_RES  49.9 1% CHIP  pkg 0402LF  page 99 : A = I3C_SPD_DDRABCD_CPU1_LVC1_SCL_1 ; B = I3C_SPD_DDRABCD_CPU1_LVC1_SCL
PC492_P1_7  Q_CAP  22UF 16V 20% X6S  pkg C0805  page 288 : A = SW_P12V_PVCCIN_CPU1_FLT ; B = GND

(kicad_pcb
	(version 20260206)
	(generator "pcbnew")
	(generator_version "10.0")
	(general
		(thickness 1.6)
		(legacy_teardrops no)
	)
	(paper "A4")
	(title_block
		(title "03242023_DA0F0TMBIJ0_F0T_Motherboard_J_brd_V01_OCP.brd")
		(comment 1 "Grand Teton / footprints 5167-5169 of 6105")
	)
	(layers
		(0 "F.Cu" signal "TOP")
		(4 "In1.Cu" signal "GND")
		(6 "In2.Cu" signal "IN1")
		(8 "In3.Cu" signal "GND1")
		(10 "In4.Cu" signal "IN2")
		(12 "In5.Cu" signal "GND2")
		(14 "In6.Cu" signal "IN3")
		(16 "In7.Cu" signal "GND3")
		(18 "In8.Cu" signal "VCC")
		(20 "In9.Cu" signal "VCC1")
		(22 "In10.Cu" signal "GND4")
		(24 "In11.Cu" signal "IN4")
		(26 "In12.Cu" signal "GND5")
		(28 "In13.Cu" signal "IN5")
		(30 "In14.Cu" signal "GND6")
		(32 "In15.Cu" signal "IN6")
		(34 "In16.Cu" signal "GND7")
		(2 "B.Cu" signal "BOTTOM")
		(9 "F.Adhes" user "F.Adhesive")
		(11 "B.Adhes" user "B.Adhesive")
		(13 "F.Paste" user "Package Geometry/Pastemask Top")
		(15 "B.Paste" user "Package Geometry/Pastemask Bottom")
		(5 "F.SilkS" user "Ref Des/Silkscreen Top")
		(7 "B.SilkS" user "Ref Des/Silkscreen Bottom")
		(1 "F.Mask" user "Board Geometry/Soldermask Top")
		(3 "B.Mask" user "Board Geometry/Soldermask Bottom")
		(17 "Dwgs.User" user "User.Drawings")
		(19 "Cmts.User" user "User.Comments")
		(21 "Eco1.User" user "User.Eco1")
		(23 "Eco2.User" user "User.Eco2")
		(25 "Edge.Cuts" user "Board Geometry/Outline")
		(27 "Margin" user)
		(31 "F.CrtYd" user "Package Geometry/Place Bound Top")
		(29 "B.CrtYd" user "Package Geometry/Place Bound Bottom")
		(35 "F.Fab" user "Ref Des/Assembly Top")
		(33 "B.Fab" user "Ref Des/Assembly Bottom")
	)
	(footprint ""
		(layer "B.Cu")
		(at 284.446726 -193.691256 -90)
		(property "Reference" "R706"
			(at 0 0 90)
			(layer "B.SilkS")
			(hide yes)
			(effects
				(font
					(size 1.27 1.27)
				)
				(justify mirror)
			)
		)
		(property "Value" ""
			(at 0 0 90)
			(layer "B.Fab")
			(effects
				(font
					(size 1.27 1.27)
				)
				(justify mirror)
			)
		)
		(duplicate_pad_numbers_are_jumpers no)
		(fp_line
			(start -0.7874 0.4064)
			(end 0.7874 0.4064)
			(stroke
				(width 0.1524)
				(type default)
			)
			(layer "B.SilkS")
		)
		(fp_line
			(start 0.7874 0.4064)
			(end 0.7874 -0.4064)
			(stroke
				(width 0.1524)
				(type default)
			)
			(layer "B.SilkS")
		)
		(fp_line
			(start -0.7874 -0.4064)
			(end -0.7874 0.4064)
			(stroke
				(width 0.1524)
				(type default)
			)
			(layer "B.SilkS")
		)
		(fp_line
			(start 0.7874 -0.4064)
			(end -0.7874 -0.4064)
			(stroke
				(width 0.1524)
				(type default)
			)
			(layer "B.SilkS")
		)
		(fp_line
			(start -0.67945 0.3048)
			(end -0.120396 0.3048)
			(stroke
				(width 0.1)
				(type default)
			)
			(layer "B.Fab")
		)
		(fp_line
			(start -0.120396 0.3048)
			(end -0.120396 0.2794)
			(stroke
				(width 0.1)
				(type default)
			)
			(layer "B.Fab")
		)
		(fp_line
			(start 0.12065 0.3048)
			(end 0.67945 0.3048)
			(stroke
				(width 0.1)
				(type default)
			)
			(layer "B.Fab")
		)
		(fp_line
			(start 0.67945 0.3048)
			(end 0.67945 -0.305054)
			(stroke
				(width 0.1)
				(type default)
			)
			(layer "B.Fab")
		)
		(fp_line
			(start -0.120396 0.2794)
			(end 0.12065 0.2794)
			(stroke
				(width 0.1)
				(type default)
			)
			(layer "B.Fab")
		)
		(fp_line
			(start 0.12065 0.2794)
			(end 0.12065 0.3048)
			(stroke
				(width 0.1)
				(type default)
			)
			(layer "B.Fab")
		)
		(fp_line
			(start -0.12065 -0.2794)
			(end -0.12065 -0.3048)
			(stroke
				(width 0.1)
				(type default)
			)
			(layer "B.Fab")
		)
		(fp_line
			(start 0.12065 -0.2794)
			(end -0.12065 -0.2794)
			(stroke
				(width 0.1)
				(type default)
			)
			(layer "B.Fab")
		)
		(fp_line
			(start -0.67945 -0.3048)
			(end -0.67945 0.3048)
			(stroke
				(width 0.1)
				(type default)
			)
			(layer "B.Fab")
		)
		(fp_line
			(start -0.12065 -0.3048)
			(end -0.67945 -0.3048)
			(stroke
				(width 0.1)
				(type default)
			)
			(layer "B.Fab")
		)
		(fp_line
			(start 0.12065 -0.305054)
			(end 0.12065 -0.2794)
			(stroke
				(width 0.1)
				(type default)
			)
			(layer "B.Fab")
		)
		(fp_line
			(start 0.67945 -0.305054)
			(end 0.12065 -0.305054)
			(stroke
				(width 0.1)
				(type default)
			)
			(layer "B.Fab")
		)
		(pad "1" smd circle
			(at 0.40005 0 90)
			(size 0 0)
			(layers "B.Cu" "B.Mask" "B.Paste")
			(net "RST_PLD_CPU0_DRAM_AB_N")
		)
		(pad "2" smd circle
			(at -0.40005 0 90)
			(size 0 0)
			(layers "B.Cu" "B.Mask" "B.Paste")
			(net "GND")
		)
	)
	(footprint ""
		(layer "B.Cu")
		(at 57.88152 -315.539882)
		(property "Reference" "R3892"
			(at 0 0 0)
			(layer "B.SilkS")
			(hide yes)
			(effects
				(font
					(size 1.27 1.27)
				)
				(justify mirror)
			)
		)
		(property "Value" ""
			(at 0 0 0)
			(layer "B.Fab")
			(effects
				(font
					(size 1.27 1.27)
				)
				(justify mirror)
			)
		)
		(duplicate_pad_numbers_are_jumpers no)
		(fp_line
			(start -0.7874 -0.4064)
			(end -0.7874 0.4064)
			(stroke
				(width 0.1524)
				(type default)
			)
			(layer "B.SilkS")
		)
		(fp_line
			(start -0.7874 0.4064)
			(end 0.7874 0.4064)
			(stroke
				(width 0.1524)
				(type default)
			)
			(layer "B.SilkS")
		)
		(fp_line
			(start 0.7874 -0.4064)
			(end -0.7874 -0.4064)
			(stroke
				(width 0.1524)
				(type default)
			)
			(layer "B.SilkS")
		)
		(fp_line
			(start 0.7874 0.4064)
			(end 0.7874 -0.4064)
			(stroke
				(width 0.1524)
				(type default)
			)
			(layer "B.SilkS")
		)
		(fp_line
			(start -0.67945 -0.3048)
			(end -0.67945 0.3048)
			(stroke
				(width 0.1)
				(type default)
			)
			(layer "B.Fab")
		)
		(fp_line
			(start -0.67945 0.3048)
			(end -0.120396 0.3048)
			(stroke
				(width 0.1)
				(type default)
			)
			(layer "B.Fab")
		)
		(fp_line
			(start -0.12065 -0.3048)
			(end -0.67945 -0.3048)
			(stroke
				(width 0.1)
				(type default)
			)
			(layer "B.Fab")
		)
		(fp_line
			(start -0.12065 -0.2794)
			(end -0.12065 -0.3048)
			(stroke
				(width 0.1)
				(type default)
			)
			(layer "B.Fab")
		)
		(fp_line
			(start -0.120396 0.2794)
			(end 0.12065 0.2794)
			(stroke
				(width 0.1)
				(type default)
			)
			(layer "B.Fab")
		)
		(fp_line
			(start -0.120396 0.3048)
			(end -0.120396 0.2794)
			(stroke
				(width 0.1)
				(type default)
			)
			(layer "B.Fab")
		)
		(fp_line
			(start 0.12065 -0.305054)
			(end 0.12065 -0.2794)
			(stroke
				(width 0.1)
				(type default)
			)
			(layer "B.Fab")
		)
		(fp_line
			(start 0.12065 -0.2794)
			(end -0.12065 -0.2794)
			(stroke
				(width 0.1)
				(type default)
			)
			(layer "B.Fab")
		)
		(fp_line
			(start 0.12065 0.2794)
			(end 0.12065 0.3048)
			(stroke
				(width 0.1)
				(type default)
			)
			(layer "B.Fab")
		)
		(fp_line
			(start 0.12065 0.3048)
			(end 0.67945 0.3048)
			(stroke
				(width 0.1)
				(type default)
			)
			(layer "B.Fab")
		)
		(fp_line
			(start 0.67945 -0.305054)
			(end 0.12065 -0.305054)
			(stroke
				(width 0.1)
				(type default)
			)
			(layer "B.Fab")
		)
		(fp_line
			(start 0.67945 0.3048)
			(end 0.67945 -0.305054)
			(stroke
				(width 0.1)
				(type default)
			)
			(layer "B.Fab")
		)
		(pad "1" smd circle
			(at 0.40005 0 180)
			(size 0 0)
			(layers "B.Cu" "B.Mask" "B.Paste")
			(net "I3C_SPD_DDRABCD_CPU1_LVC1_SCL_1")
		)
		(pad "2" smd circle
			(at -0.40005 0 180)
			(size 0 0)
			(layers "B.Cu" "B.Mask" "B.Paste")
			(net "I3C_SPD_DDRABCD_CPU1_LVC1_SCL")
		)
	)
	(footprint ""
		(layer "B.Cu")
		(at 83.933538 -342.936576 90)
		(property "Reference" "PC492_P1_7"
			(at 0 0 90)
			(layer "B.SilkS")
			(hide yes)
			(effects
				(font
					(size 1.27 1.27)
				)
				(justify mirror)
			)
		)
		(property "Value" ""
			(at 0 0 90)
			(layer "B.Fab")
			(effects
				(font
					(size 1.27 1.27)
				)
				(justify mirror)
			)
		)
		(duplicate_pad_numbers_are_jumpers no)
		(fp_line
			(start 1.524 -0.762)
			(end -1.524 -0.762)
			(stroke
				(width 0.1524)
				(type default)
			)
			(layer "B.SilkS")
		)
		(fp_line
			(start -1.524 -0.762)
			(end -1.524 0.762)
			(stroke
				(width 0.1524)
				(type default)
			)
			(layer "B.SilkS")
		)
		(fp_line
			(start 1.524 0.762)
			(end 1.524 -0.762)
			(stroke
				(width 0.1524)
				(type default)
			)
			(layer "B.SilkS")
		)
		(fp_line
			(start -1.524 0.762)
			(end 1.524 0.762)
			(stroke
				(width 0.1524)
				(type default)
			)
			(layer "B.SilkS")
		)
		(fp_line
			(start 1.1049 -0.724916)
			(end 1.1049 0.724916)
			(stroke
				(width 0.1)
				(type default)
			)
			(layer "B.Fab")
		)
		(fp_line
			(start -1.1049 -0.724916)
			(end 1.1049 -0.724916)
			(stroke
				(width 0.1)
				(type default)
			)
			(layer "B.Fab")
		)
		(fp_line
			(start 1.1049 0.724916)
			(end -1.1049 0.724916)
			(stroke
				(width 0.1)
				(type default)
			)
			(layer "B.Fab")
		)
		(fp_line
			(start -1.1049 0.724916)
			(end -1.1049 -0.724916)
			(stroke
				(width 0.1)
				(type default)
			)
			(layer "B.Fab")
		)
		(pad "1" smd rect
			(at 0.889 0 90)
			(size 1.016 1.27)
			(layers "B.Cu" "B.Mask" "B.Paste")
			(net "SW_P12V_PVCCIN_CPU1_FLT")
		)
		(pad "2" smd rect
			(at -0.889 0 90)
			(size 1.016 1.27)
			(layers "B.Cu" "B.Mask" "B.Paste")
			(net "GND")
		)
	)
)
